# BASEBOARD_FAB2 (Tioga Pass) — schematic netlist excerpt (pin names and nets, part order shuffled) for the footprints in the layout excerpt that follows; sources: Cadence DE-HDL packaged netlist, KiCad conversion of Wiwynn_Tioga_Pass_MB.brd

R5P3  RES  49.9 1% CHIP  pkg 0402  page 90 : A = PD_CPU0_TEST13 ; B = GND
R1U21  RES  2.7K 1% CHIP  pkg 0402  page 164 : A = P3V3_STBY ; B = FM_BOARD_SKU_ID3
R3W2  RES  100.0K 1% CHIP  pkg 0402  page 249 : A = BMC_TPM_HW_C_RST ; B = GND

(kicad_pcb
	(version 20260206)
	(generator "pcbnew")
	(generator_version "10.0")
	(general
		(thickness 1.6)
		(legacy_teardrops no)
	)
	(paper "A4")
	(title_block
		(title "Wiwynn_Tioga_Pass_MB.brd")
		(comment 1 "Tioga Pass / footprints 3127-3129 of 4770")
	)
	(layers
		(0 "F.Cu" signal "TOP")
		(4 "In1.Cu" signal "L2GND")
		(6 "In2.Cu" signal "L3")
		(8 "In3.Cu" signal "L4GND")
		(10 "In4.Cu" signal "L5")
		(12 "In5.Cu" signal "L6GND")
		(14 "In6.Cu" signal "L7VCC")
		(16 "In7.Cu" signal "L8VCC")
		(18 "In8.Cu" signal "L9GND")
		(20 "In9.Cu" signal "L10")
		(22 "In10.Cu" signal "L11GND")
		(24 "In11.Cu" signal "L12")
		(26 "In12.Cu" signal "L13GND")
		(2 "B.Cu" signal "BOTTOM")
		(9 "F.Adhes" user "F.Adhesive")
		(11 "B.Adhes" user "B.Adhesive")
		(13 "F.Paste" user "Package Geometry/Pastemask Top")
		(15 "B.Paste" user "Package Geometry/Pastemask Bottom")
		(5 "F.SilkS" user "Ref Des/Silkscreen Top")
		(7 "B.SilkS" user "Ref Des/Silkscreen Bottom")
		(1 "F.Mask" user "Board Geometry/Soldermask Top")
		(3 "B.Mask" user "Board Geometry/Soldermask Bottom")
		(17 "Dwgs.User" user "User.Drawings")
		(19 "Cmts.User" user "User.Comments")
		(21 "Eco1.User" user "User.Eco1")
		(23 "Eco2.User" user "User.Eco2")
		(25 "Edge.Cuts" user "Board Geometry/Outline")
		(27 "Margin" user)
		(31 "F.CrtYd" user "Package Geometry/Place Bound Top")
		(29 "B.CrtYd" user "Package Geometry/Place Bound Bottom")
		(35 "F.Fab" user "Ref Des/Assembly Top")
		(33 "B.Fab" user "Ref Des/Assembly Bottom")
	)
	(footprint ""
		(layer "B.Cu")
		(at 451.030594 -17.9451 -90)
		(property "Reference" "R3W2"
			(at 0.8382 -0.67818 270)
			(unlocked yes)
			(layer "B.SilkS")
			(effects
				(font
					(size 0.4064 0.254)
					(thickness 0.1524)
				)
				(justify left mirror)
			)
		)
		(property "Value" ""
			(at 0 0 90)
			(layer "B.Fab")
			(effects
				(font
					(size 1.27 1.27)
				)
				(justify mirror)
			)
		)
		(duplicate_pad_numbers_are_jumpers no)
		(fp_poly
			(pts
				(xy 0.2794 -0.1016) (xy -0.2794 -0.1016) (xy -0.2794 0.9906) (xy 0.2794 0.9906)
			)
			(stroke
				(width 0)
				(type default)
			)
			(fill no)
			(layer "B.CrtYd")
		)
		(fp_line
			(start -0.2794 0.9906)
			(end -0.2794 -0.1016)
			(stroke
				(width 0.1)
				(type default)
			)
			(layer "B.Fab")
		)
		(fp_line
			(start 0.2794 0.9906)
			(end -0.2794 0.9906)
			(stroke
				(width 0.1)
				(type default)
			)
			(layer "B.Fab")
		)
		(fp_line
			(start -0.2794 -0.1016)
			(end 0.2794 -0.1016)
			(stroke
				(width 0.1)
				(type default)
			)
			(layer "B.Fab")
		)
		(fp_line
			(start 0.2794 -0.1016)
			(end 0.2794 0.9906)
			(stroke
				(width 0.1)
				(type default)
			)
			(layer "B.Fab")
		)
		(pad "1" smd rect
			(at 0 0 90)
			(size 0.508 0.508)
			(layers "B.Cu" "B.Mask" "B.Paste")
			(net "BMC_TPM_HW_C_RST")
		)
		(pad "2" smd rect
			(at 0 0.889 90)
			(size 0.508 0.508)
			(layers "B.Cu" "B.Mask" "B.Paste")
			(net "GND")
		)
		(zone
			(layer "B.Cu")
			(hatch none 0.5)
			(connect_pads
				(clearance 0)
			)
			(min_thickness 0.25)
			(keepout
				(tracks not_allowed)
				(vias allowed)
				(pads allowed)
				(copperpour not_allowed)
				(footprints allowed)
			)
			(placement
				(enabled no)
				(sheetname "")
			)
			(fill
				(thermal_gap 0.5)
				(thermal_bridge_width 0.5)
				(island_removal_mode 0)
			)
			(polygon
				(pts
					(xy 450.395594 -17.6911) (xy 450.395594 -18.1991) (xy 450.776594 -18.1991) (xy 450.776594 -17.6911)
				)
			)
		)
		(zone
			(layer "B.Cu")
			(hatch none 0.5)
			(connect_pads
				(clearance 0)
			)
			(min_thickness 0.25)
			(keepout
				(tracks allowed)
				(vias not_allowed)
				(pads allowed)
				(copperpour not_allowed)
				(footprints allowed)
			)
			(placement
				(enabled no)
				(sheetname "")
			)
			(fill
				(thermal_gap 0.5)
				(thermal_bridge_width 0.5)
				(island_removal_mode 0)
			)
			(polygon
				(pts
					(xy 450.776594 -17.6911) (xy 450.776594 -18.1991) (xy 450.395594 -18.1991) (xy 450.395594 -17.6911)
				)
			)
		)
	)
	(footprint ""
		(layer "B.Cu")
		(at 460.9846 -35.7124 -90)
		(property "Reference" "R1U21"
			(at 0 0 90)
			(layer "B.SilkS")
			(hide yes)
			(effects
				(font
					(size 1.27 1.27)
				)
				(justify mirror)
			)
		)
		(property "Value" ""
			(at 0 0 90)
			(layer "B.Fab")
			(effects
				(font
					(size 1.27 1.27)
				)
				(justify mirror)
			)
		)
		(duplicate_pad_numbers_are_jumpers no)
		(fp_poly
			(pts
				(xy 0.2794 -0.1016) (xy -0.2794 -0.1016) (xy -0.2794 0.9906) (xy 0.2794 0.9906)
			)
			(stroke
				(width 0)
				(type default)
			)
			(fill no)
			(layer "B.CrtYd")
		)
		(fp_line
			(start -0.2794 0.9906)
			(end -0.2794 -0.1016)
			(stroke
				(width 0.1)
				(type default)
			)
			(layer "B.Fab")
		)
		(fp_line
			(start 0.2794 0.9906)
			(end -0.2794 0.9906)
			(stroke
				(width 0.1)
				(type default)
			)
			(layer "B.Fab")
		)
		(fp_line
			(start -0.2794 -0.1016)
			(end 0.2794 -0.1016)
			(stroke
				(width 0.1)
				(type default)
			)
			(layer "B.Fab")
		)
		(fp_line
			(start 0.2794 -0.1016)
			(end 0.2794 0.9906)
			(stroke
				(width 0.1)
				(type default)
			)
			(layer "B.Fab")
		)
		(pad "1" smd rect
			(at 0 0 90)
			(size 0.508 0.508)
			(layers "B.Cu" "B.Mask" "B.Paste")
			(net "P3V3_STBY")
		)
		(pad "2" smd rect
			(at 0 0.889 90)
			(size 0.508 0.508)
			(layers "B.Cu" "B.Mask" "B.Paste")
			(net "FM_BOARD_SKU_ID3")
		)
		(zone
			(layer "B.Cu")
			(hatch none 0.5)
			(connect_pads
				(clearance 0)
			)
			(min_thickness 0.25)
			(keepout
				(tracks not_allowed)
				(vias allowed)
				(pads allowed)
				(copperpour not_allowed)
				(footprints allowed)
			)
			(placement
				(enabled no)
				(sheetname "")
			)
			(fill
				(thermal_gap 0.5)
				(thermal_bridge_width 0.5)
				(island_removal_mode 0)
			)
			(polygon
				(pts
					(xy 460.3496 -35.4584) (xy 460.3496 -35.9664) (xy 460.7306 -35.9664) (xy 460.7306 -35.4584)
				)
			)
		)
		(zone
			(layer "B.Cu")
			(hatch none 0.5)
			(connect_pads
				(clearance 0)
			)
			(min_thickness 0.25)
			(keepout
				(tracks allowed)
				(vias not_allowed)
				(pads allowed)
				(copperpour not_allowed)
				(footprints allowed)
			)
			(placement
				(enabled no)
				(sheetname "")
			)
			(fill
				(thermal_gap 0.5)
				(thermal_bridge_width 0.5)
				(island_removal_mode 0)
			)
			(polygon
				(pts
					(xy 460.7306 -35.4584) (xy 460.7306 -35.9664) (xy 460.3496 -35.9664) (xy 460.3496 -35.4584)
				)
			)
		)
	)
	(footprint ""
		(layer "B.Cu")
		(at 245.14302 -86.57336 -90)
		(property "Reference" "R5P3"
			(at 0 0 90)
			(layer "B.SilkS")
			(hide yes)
			(effects
				(font
					(size 1.27 1.27)
				)
				(justify mirror)
			)
		)
		(property "Value" ""
			(at 0 0 90)
			(layer "B.Fab")
			(effects
				(font
					(size 1.27 1.27)
				)
				(justify mirror)
			)
		)
		(duplicate_pad_numbers_are_jumpers no)
		(fp_poly
			(pts
				(xy 0.2794 -0.1016) (xy -0.2794 -0.1016) (xy -0.2794 0.9906) (xy 0.2794 0.9906)
			)
			(stroke
				(width 0)
				(type default)
			)
			(fill no)
			(layer "B.CrtYd")
		)
		(fp_line
			(start -0.2794 0.9906)
			(end -0.2794 -0.1016)
			(stroke
				(width 0.1)
				(type default)
			)
			(layer "B.Fab")
		)
		(fp_line
			(start 0.2794 0.9906)
			(end -0.2794 0.9906)
			(stroke
				(width 0.1)
				(type default)
			)
			(layer "B.Fab")
		)
		(fp_line
			(start -0.2794 -0.1016)
			(end 0.2794 -0.1016)
			(stroke
				(width 0.1)
				(type default)
			)
			(layer "B.Fab")
		)
		(fp_line
			(start 0.2794 -0.1016)
			(end 0.2794 0.9906)
			(stroke
				(width 0.1)
				(type default)
			)
			(layer "B.Fab")
		)
		(pad "1" smd rect
			(at 0 0 90)
			(size 0.508 0.508)
			(layers "B.Cu" "B.Mask" "B.Paste")
			(net "PD_CPU0_TEST13")
		)
		(pad "2" smd rect
			(at 0 0.889 90)
			(size 0.508 0.508)
			(layers "B.Cu" "B.Mask" "B.Paste")
			(net "GND")
		)
		(zone
			(layer "B.Cu")
			(hatch none 0.5)
			(connect_pads
				(clearance 0)
			)
			(min_thickness 0.25)
			(keepout
				(tracks not_allowed)
				(vias allowed)
				(pads allowed)
				(copperpour not_allowed)
				(footprints allowed)
			)
			(placement
				(enabled no)
				(sheetname "")
			)
			(fill
				(thermal_gap 0.5)
				(thermal_bridge_width 0.5)
				(island_removal_mode 0)
			)
			(polygon
				(pts
					(xy 244.50802 -86.31936) (xy 244.50802 -86.82736) (xy 244.88902 -86.82736) (xy 244.88902 -86.31936)
				)
			)
		)
		(zone
			(layer "B.Cu")
			(hatch none 0.5)
			(connect_pads
				(clearance 0)
			)
			(min_thickness 0.25)
			(keepout
				(tracks allowed)
				(vias not_allowed)
				(pads allowed)
				(copperpour not_allowed)
				(footprints allowed)
			)
			(placement
				(enabled no)
				(sheetname "")
			)
			(fill
				(thermal_gap 0.5)
				(thermal_bridge_width 0.5)
				(island_removal_mode 0)
			)
			(polygon
				(pts
					(xy 244.88902 -86.31936) (xy 244.88902 -86.82736) (xy 244.50802 -86.82736) (xy 244.50802 -86.31936)
				)
			)
		)
	)
)
